(kicad_pcb
	(version 20260206)
	(generator "pcbnew")
	(generator_version "10.0")
	(general
		(thickness 1.6)
		(legacy_teardrops no)
	)
	(paper "A4")
	(title_block
		(title "04192023_DAF0TMB3IC0_F0TG_MB_C_brd_V02_OCP.brd")
		(comment 1 "Grand Teton / footprints 1100-1103 of 8354")
	)
	(layers
		(0 "F.Cu" signal "TOP")
		(4 "In1.Cu" signal "GND")
		(6 "In2.Cu" signal "IN1")
		(8 "In3.Cu" signal "GND1")
		(10 "In4.Cu" signal "IN2")
		(12 "In5.Cu" signal "GND2")
		(14 "In6.Cu" signal "IN3")
		(16 "In7.Cu" signal "GND3")
		(18 "In8.Cu" signal "VCC")
		(20 "In9.Cu" signal "VCC1")
		(22 "In10.Cu" signal "GND4")
		(24 "In11.Cu" signal "IN4")
		(26 "In12.Cu" signal "GND5")
		(28 "In13.Cu" signal "IN5")
		(30 "In14.Cu" signal "GND6")
		(32 "In15.Cu" signal "IN6")
		(34 "In16.Cu" signal "GND7")
		(2 "B.Cu" signal "BOTTOM")
		(9 "F.Adhes" user "F.Adhesive")
		(11 "B.Adhes" user "B.Adhesive")
		(13 "F.Paste" user "Package Geometry/Pastemask Top")
		(15 "B.Paste" user "Package Geometry/Pastemask Bottom")
		(5 "F.SilkS" user "Ref Des/Silkscreen Top")
		(7 "B.SilkS" user "Ref Des/Silkscreen Bottom")
		(1 "F.Mask" user "Board Geometry/Soldermask Top")
		(3 "B.Mask" user "Board Geometry/Soldermask Bottom")
		(17 "Dwgs.User" user "User.Drawings")
		(19 "Cmts.User" user "User.Comments")
		(21 "Eco1.User" user "User.Eco1")
		(23 "Eco2.User" user "User.Eco2")
		(25 "Edge.Cuts" user "Board Geometry/Outline")
		(27 "Margin" user)
		(31 "F.CrtYd" user "Package Geometry/Place Bound Top")
		(29 "B.CrtYd" user "Package Geometry/Place Bound Bottom")
		(35 "F.Fab" user "Ref Des/Assembly Top")
		(33 "B.Fab" user "Ref Des/Assembly Bottom")
	)
	(footprint ""
		(layer "F.Cu")
		(at 184.455054 -168.317926 -90)
		(property "Reference" "R1296"
			(at 0 0 270)
			(layer "F.SilkS")
			(hide yes)
			(effects
				(font
					(size 1.27 1.27)
				)
			)
		)
		(property "Value" ""
			(at 0 0 270)
			(layer "F.Fab")
			(effects
				(font
					(size 1.27 1.27)
				)
			)
		)
		(duplicate_pad_numbers_are_jumpers no)
		(fp_line
			(start -0.7874 0.4064)
			(end -0.7874 -0.4064)
			(stroke
				(width 0.1524)
				(type default)
			)
			(layer "F.SilkS")
		)
		(fp_line
			(start 0.7874 0.4064)
			(end -0.7874 0.4064)
			(stroke
				(width 0.1524)
				(type default)
			)
			(layer "F.SilkS")
		)
		(fp_line
			(start -0.7874 -0.4064)
			(end 0.7874 -0.4064)
			(stroke
				(width 0.1524)
				(type default)
			)
			(layer "F.SilkS")
		)
		(fp_line
			(start 0.7874 -0.4064)
			(end 0.7874 0.4064)
			(stroke
				(width 0.1524)
				(type default)
			)
			(layer "F.SilkS")
		)
		(fp_line
			(start -0.67945 0.3048)
			(end -0.67945 -0.305054)
			(stroke
				(width 0.1)
				(type default)
			)
			(layer "F.Fab")
		)
		(fp_line
			(start -0.12065 0.3048)
			(end -0.67945 0.3048)
			(stroke
				(width 0.1)
				(type default)
			)
			(layer "F.Fab")
		)
		(fp_line
			(start 0.120396 0.3048)
			(end 0.120396 0.2794)
			(stroke
				(width 0.1)
				(type default)
			)
			(layer "F.Fab")
		)
		(fp_line
			(start 0.67945 0.3048)
			(end 0.120396 0.3048)
			(stroke
				(width 0.1)
				(type default)
			)
			(layer "F.Fab")
		)
		(fp_line
			(start -0.12065 0.2794)
			(end -0.12065 0.3048)
			(stroke
				(width 0.1)
				(type default)
			)
			(layer "F.Fab")
		)
		(fp_line
			(start 0.120396 0.2794)
			(end -0.12065 0.2794)
			(stroke
				(width 0.1)
				(type default)
			)
			(layer "F.Fab")
		)
		(fp_line
			(start -0.12065 -0.2794)
			(end 0.12065 -0.2794)
			(stroke
				(width 0.1)
				(type default)
			)
			(layer "F.Fab")
		)
		(fp_line
			(start 0.12065 -0.2794)
			(end 0.12065 -0.3048)
			(stroke
				(width 0.1)
				(type default)
			)
			(layer "F.Fab")
		)
		(fp_line
			(start 0.12065 -0.3048)
			(end 0.67945 -0.3048)
			(stroke
				(width 0.1)
				(type default)
			)
			(layer "F.Fab")
		)
		(fp_line
			(start 0.67945 -0.3048)
			(end 0.67945 0.3048)
			(stroke
				(width 0.1)
				(type default)
			)
			(layer "F.Fab")
		)
		(fp_line
			(start -0.67945 -0.305054)
			(end -0.12065 -0.305054)
			(stroke
				(width 0.1)
				(type default)
			)
			(layer "F.Fab")
		)
		(fp_line
			(start -0.12065 -0.305054)
			(end -0.12065 -0.2794)
			(stroke
				(width 0.1)
				(type default)
			)
			(layer "F.Fab")
		)
		(pad "1" smd rect
			(at -0.40005 0 90)
			(size 0.4572 0.508)
			(layers "F.Cu" "F.Mask" "F.Paste")
			(net "I3C_SPD_DDRGL_CPU1_SDA")
		)
		(pad "2" smd rect
			(at 0.40005 0 90)
			(size 0.4572 0.508)
			(layers "F.Cu" "F.Mask" "F.Paste")
			(net "I3C_SPD_DDRGL_CPU1_LVC1_SDA")
		)
	)
	(footprint ""
		(layer "F.Cu")
		(at 184.337198 -420.329868 90)
		(property "Reference" "U181"
			(at -0.339344 -7.867396 90)
			(unlocked yes)
			(layer "F.SilkS")
			(effects
				(font
					(size 0.7874 0.5842)
					(thickness 0.1524)
				)
				(justify left)
			)
		)
		(property "Value" ""
			(at 0 0 90)
			(layer "F.Fab")
			(effects
				(font
					(size 1.27 1.27)
				)
			)
		)
		(duplicate_pad_numbers_are_jumpers no)
		(fp_line
			(start 2.097532 -3.949954)
			(end 1.409954 -3.949954)
			(stroke
				(width 0.1524)
				(type default)
			)
			(layer "F.SilkS")
		)
		(fp_line
			(start 1.409954 -3.949954)
			(end 0 -2.54)
			(stroke
				(width 0.1524)
				(type default)
			)
			(layer "F.SilkS")
		)
		(fp_line
			(start -1.409954 -3.949954)
			(end -2.097532 -3.949954)
			(stroke
				(width 0.1524)
				(type default)
			)
			(layer "F.SilkS")
		)
		(fp_line
			(start -2.097532 -3.949954)
			(end -2.097532 3.949954)
			(stroke
				(width 0.1524)
				(type default)
			)
			(layer "F.SilkS")
		)
		(fp_line
			(start 0 -2.54)
			(end -1.409954 -3.949954)
			(stroke
				(width 0.1524)
				(type default)
			)
			(layer "F.SilkS")
		)
		(fp_line
			(start 2.097532 3.949954)
			(end 2.097532 -3.949954)
			(stroke
				(width 0.1524)
				(type default)
			)
			(layer "F.SilkS")
		)
		(fp_line
			(start -2.097532 3.949954)
			(end 2.097532 3.949954)
			(stroke
				(width 0.1524)
				(type default)
			)
			(layer "F.SilkS")
		)
		(fp_poly
			(pts
				(xy -4.509262 -5.070856) (xy -3.67538 -5.650992) (xy -3.512058 -4.527042)
			)
			(stroke
				(width 0)
				(type default)
			)
			(fill yes)
			(layer "F.SilkS")
		)
		(fp_line
			(start 2.249932 -3.949954)
			(end -2.249932 -3.949954)
			(stroke
				(width 0.1)
				(type default)
			)
			(layer "F.Fab")
		)
		(fp_line
			(start -2.249932 -3.949954)
			(end -2.249932 3.949954)
			(stroke
				(width 0.1)
				(type default)
			)
			(layer "F.Fab")
		)
		(fp_line
			(start 2.249932 3.949954)
			(end 2.249932 -3.949954)
			(stroke
				(width 0.1)
				(type default)
			)
			(layer "F.Fab")
		)
		(fp_line
			(start -2.249932 3.949954)
			(end 2.249932 3.949954)
			(stroke
				(width 0.1)
				(type default)
			)
			(layer "F.Fab")
		)
		(fp_poly
			(pts
				(xy -4.7498 -4.182872) (xy -4.7498 -3.166872) (xy -3.7338 -3.674872)
			)
			(stroke
				(width 0)
				(type default)
			)
			(fill yes)
			(layer "F.Fab")
		)
		(pad "1" smd rect
			(at -2.925064 -3.674872)
			(size 0.6096 1.3716)
			(layers "F.Cu" "F.Mask" "F.Paste")
			(net "PU_U181_INT")
		)
		(pad "2" smd rect
			(at -2.925064 -2.925064)
			(size 0.4064 1.3716)
			(layers "F.Cu" "F.Mask" "F.Paste")
			(net "TCA9539_0_ADD1")
		)
		(pad "3" smd rect
			(at -2.925064 -2.275078)
			(size 0.4064 1.3716)
			(layers "F.Cu" "F.Mask" "F.Paste")
			(net "PU_RST_SMB_U181_N")
		)
		(pad "4" smd rect
			(at -2.925064 -1.625092)
			(size 0.4064 1.3716)
			(layers "F.Cu" "F.Mask" "F.Paste")
			(net "RST_USB_HUB_N")
		)
		(pad "5" smd rect
			(at -2.925064 -0.975106)
			(size 0.4064 1.3716)
			(layers "F.Cu" "F.Mask" "F.Paste")
			(net "RST_SWB_BIC_N")
		)
		(pad "6" smd rect
			(at -2.925064 -0.32512)
			(size 0.4064 1.3716)
			(layers "F.Cu" "F.Mask" "F.Paste")
			(net "TP_TCA9539_0_P0_2")
		)
		(pad "7" smd rect
			(at -2.925064 0.32512)
			(size 0.4064 1.3716)
			(layers "F.Cu" "F.Mask" "F.Paste")
			(net "TP_TCA9539_0_P0_3")
		)
		(pad "8" smd rect
			(at -2.925064 0.975106)
			(size 0.4064 1.3716)
			(layers "F.Cu" "F.Mask" "F.Paste")
			(net "PRSNT_SWB_ISO_R1_N")
		)
		(pad "9" smd rect
			(at -2.925064 1.625092)
			(size 0.4064 1.3716)
			(layers "F.Cu" "F.Mask" "F.Paste")
			(net "GPU_PRSNT_N_ISO_R1")
		)
		(pad "10" smd rect
			(at -2.925064 2.275078)
			(size 0.4064 1.3716)
			(layers "F.Cu" "F.Mask" "F.Paste")
			(net "PRSNT_CABLE_GPU_B3_ISO_R1_N")
		)
		(pad "11" smd rect
			(at -2.925064 2.925064)
			(size 0.4064 1.3716)
			(layers "F.Cu" "F.Mask" "F.Paste")
			(net "PRSNT_CABLE_SWB_B2_ISO_R_N")
		)
		(pad "12" smd rect
			(at -2.925064 3.674872)
			(size 0.6096 1.3716)
			(layers "F.Cu" "F.Mask" "F.Paste")
			(net "GND")
		)
		(pad "13" smd rect
			(at 2.925064 3.674872)
			(size 0.6096 1.3716)
			(layers "F.Cu" "F.Mask" "F.Paste")
			(net "PRSNT_CABLE_GPU_A2_ISO_R1_N")
		)
		(pad "14" smd rect
			(at 2.925064 2.925064)
			(size 0.4064 1.3716)
			(layers "F.Cu" "F.Mask" "F.Paste")
			(net "PRSNT_CABLE_SWB_B1_ISO_R_N")
		)
		(pad "15" smd rect
			(at 2.925064 2.275078)
			(size 0.4064 1.3716)
			(layers "F.Cu" "F.Mask" "F.Paste")
			(net "GPU_BASE_ID0_R")
		)
		(pad "16" smd rect
			(at 2.925064 1.625092)
			(size 0.4064 1.3716)
			(layers "F.Cu" "F.Mask" "F.Paste")
			(net "GPU_BASE_ID1_R")
		)
		(pad "17" smd rect
			(at 2.925064 0.975106)
			(size 0.4064 1.3716)
			(layers "F.Cu" "F.Mask" "F.Paste")
			(net "GPU_PEX_STRAP0_R")
		)
		(pad "18" smd rect
			(at 2.925064 0.32512)
			(size 0.4064 1.3716)
			(layers "F.Cu" "F.Mask" "F.Paste")
			(net "GPU_PEX_STRAP1_R")
		)
		(pad "19" smd rect
			(at 2.925064 -0.32512)
			(size 0.4064 1.3716)
			(layers "F.Cu" "F.Mask" "F.Paste")
			(net "PRSNT_CABLE_GPU_A1_ISO_R1_N")
		)
		(pad "20" smd rect
			(at 2.925064 -0.975106)
			(size 0.4064 1.3716)
			(layers "F.Cu" "F.Mask" "F.Paste")
			(net "PRSNT_CABLE_GPU_A3_ISO_R_N")
		)
		(pad "21" smd rect
			(at 2.925064 -1.625092)
			(size 0.4064 1.3716)
			(layers "F.Cu" "F.Mask" "F.Paste")
			(net "TCA9539_0_ADD0")
		)
		(pad "22" smd rect
			(at 2.925064 -2.275078)
			(size 0.4064 1.3716)
			(layers "F.Cu" "F.Mask" "F.Paste")
			(net "SMB_IOEXP_3V3AUX_SCL_R1")
		)
		(pad "23" smd rect
			(at 2.925064 -2.925064)
			(size 0.4064 1.3716)
			(layers "F.Cu" "F.Mask" "F.Paste")
			(net "SMB_IOEXP_3V3AUX_SDA_R1")
		)
		(pad "24" smd rect
			(at 2.925064 -3.674872)
			(size 0.6096 1.3716)
			(layers "F.Cu" "F.Mask" "F.Paste")
			(net "P3V3_AUX")
		)
	)
	(footprint ""
		(layer "F.Cu")
		(at 213.67496 -360.764074)
		(property "Reference" "H111"
			(at -8.086852 -7.844028 0)
			(unlocked yes)
			(layer "F.SilkS")
			(effects
				(font
					(size 0.7874 0.5842)
					(thickness 0.1524)
				)
				(justify left)
			)
		)
		(property "Value" ""
			(at 0 0 0)
			(layer "F.Fab")
			(effects
				(font
					(size 1.27 1.27)
				)
			)
		)
		(duplicate_pad_numbers_are_jumpers no)
		(fp_circle
			(center 0 0)
			(end 7.999984 0)
			(stroke
				(width 0.1524)
				(type default)
			)
			(fill no)
			(layer "F.SilkS")
		)
		(fp_circle
			(center 0 0)
			(end 7.999984 0)
			(stroke
				(width 0.1524)
				(type default)
			)
			(fill no)
			(layer "B.SilkS")
		)
		(fp_circle
			(center 0 0)
			(end 7.999984 0)
			(stroke
				(width 0.1)
				(type default)
			)
			(fill no)
			(layer "B.Fab")
		)
		(fp_circle
			(center 0 0)
			(end 7.999984 0)
			(stroke
				(width 0.1)
				(type default)
			)
			(fill no)
			(layer "F.Fab")
		)
		(pad "" np_thru_hole circle
			(at 0 0)
			(size 4.0132 4.0132)
			(drill 4.0132)
			(layers "*.Cu" "*.Mask")
			(clearance 0.381)
			(thermal_gap 0.381)
		)
		(pad "2" thru_hole circle
			(at 3.2639 0)
			(size 0.9144 0.9144)
			(drill 0.5588)
			(layers "*.Cu" "*.Mask")
			(remove_unused_layers no)
			(net "GND")
			(clearance 0.0762)
			(thermal_gap 0.0762)
		)
		(pad "3" thru_hole circle
			(at 2.307844 -2.307844)
			(size 0.9144 0.9144)
			(drill 0.5588)
			(layers "*.Cu" "*.Mask")
			(remove_unused_layers no)
			(net "GND")
			(clearance 0.0762)
			(thermal_gap 0.0762)
		)
		(pad "4" thru_hole circle
			(at 0 -3.2639)
			(size 0.9144 0.9144)
			(drill 0.5588)
			(layers "*.Cu" "*.Mask")
			(remove_unused_layers no)
			(net "GND")
			(clearance 0.0762)
			(thermal_gap 0.0762)
		)
		(pad "5" thru_hole circle
			(at -2.307844 -2.307844)
			(size 0.9144 0.9144)
			(drill 0.5588)
			(layers "*.Cu" "*.Mask")
			(remove_unused_layers no)
			(net "GND")
			(clearance 0.0762)
			(thermal_gap 0.0762)
		)
		(pad "6" thru_hole circle
			(at -3.2639 0)
			(size 0.9144 0.9144)
			(drill 0.5588)
			(layers "*.Cu" "*.Mask")
			(remove_unused_layers no)
			(net "GND")
			(clearance 0.0762)
			(thermal_gap 0.0762)
		)
		(pad "7" thru_hole circle
			(at -2.307844 2.307844)
			(size 0.9144 0.9144)
			(drill 0.5588)
			(layers "*.Cu" "*.Mask")
			(remove_unused_layers no)
			(net "GND")
			(clearance 0.0762)
			(thermal_gap 0.0762)
		)
		(pad "8" thru_hole circle
			(at 0 3.2639)
			(size 0.9144 0.9144)
			(drill 0.5588)
			(layers "*.Cu" "*.Mask")
			(remove_unused_layers no)
			(net "GND")
			(clearance 0.0762)
			(thermal_gap 0.0762)
		)
		(pad "9" thru_hole circle
			(at 2.307844 2.307844)
			(size 0.9144 0.9144)
			(drill 0.5588)
			(layers "*.Cu" "*.Mask")
			(remove_unused_layers no)
			(net "GND")
			(clearance 0.0762)
			(thermal_gap 0.0762)
		)
		(zone
			(layer "F.Cu")
			(hatch none 0.5)
			(connect_pads
				(clearance 0)
			)
			(min_thickness 0.25)
			(keepout
				(tracks not_allowed)
				(vias allowed)
				(pads allowed)
				(copperpour not_allowed)
				(footprints allowed)
			)
			(placement
				(enabled no)
				(sheetname "")
			)
			(fill
				(thermal_gap 0.5)
				(thermal_bridge_width 0.5)
				(island_removal_mode 0)
			)
			(polygon
				(pts
					(arc
						(start 213.67496 -356.496874)
						(mid 209.40776 -360.764074)
						(end 213.67496 -365.031274)
					)
					(arc
						(start 213.67496 -368.764058)
						(mid 208.018117 -366.420917)
						(end 205.674976 -360.764074)
					)
					(arc
						(start 205.674976 -360.764074)
						(mid 208.018117 -355.107231)
						(end 213.67496 -352.76409)
					)
				)
			)
		)
		(zone
			(layer "F.Cu")
			(hatch none 0.5)
			(connect_pads
				(clearance 0)
			)
			(min_thickness 0.25)
			(keepout
				(tracks not_allowed)
				(vias allowed)
				(pads allowed)
				(copperpour not_allowed)
				(footprints allowed)
			)
			(placement
				(enabled no)
				(sheetname "")
			)
			(fill
				(thermal_gap 0.5)
				(thermal_bridge_width 0.5)
				(island_removal_mode 0)
			)
			(polygon
				(pts
					(arc
						(start 213.67496 -356.496874)
						(mid 217.94216 -360.764074)
						(end 213.67496 -365.031274)
					)
					(arc
						(start 213.67496 -368.764058)
						(mid 219.331803 -366.420917)
						(end 221.674944 -360.764074)
					)
					(arc
						(start 221.674944 -360.764074)
						(mid 219.331803 -355.107231)
						(end 213.67496 -352.76409)
					)
				)
			)
		)
		(zone
			(layers "F.Cu" "B.Cu" "In1.Cu" "In2.Cu" "In3.Cu" "In4.Cu" "In5.Cu" "In6.Cu"
				"In7.Cu" "In8.Cu" "In9.Cu" "In10.Cu" "In11.Cu" "In12.Cu" "In13.Cu" "In14.Cu"
				"In15.Cu" "In16.Cu"
			)
			(hatch none 0.5)
			(connect_pads
				(clearance 0)
			)
			(min_thickness 0.25)
			(keepout
				(tracks not_allowed)
				(vias allowed)
				(pads allowed)
				(copperpour not_allowed)
				(footprints allowed)
			)
			(placement
				(enabled no)
				(sheetname "")
			)
			(fill
				(thermal_gap 0.5)
				(thermal_bridge_width 0.5)
				(island_removal_mode 0)
			)
			(polygon
				(pts
					(arc
						(start 216.18702 -360.764074)
						(mid 211.1629 -360.764074)
						(end 216.18702 -360.764074)
					)
				)
			)
		)
		(zone
			(layer "B.Cu")
			(hatch none 0.5)
			(connect_pads
				(clearance 0)
			)
			(min_thickness 0.25)
			(keepout
				(tracks not_allowed)
				(vias allowed)
				(pads allowed)
				(copperpour not_allowed)
				(footprints allowed)
			)
			(placement
				(enabled no)
				(sheetname "")
			)
			(fill
				(thermal_gap 0.5)
				(thermal_bridge_width 0.5)
				(island_removal_mode 0)
			)
			(polygon
				(pts
					(arc
						(start 213.67496 -365.285274)
						(mid 209.15376 -360.764074)
						(end 213.67496 -356.242874)
					)
					(arc
						(start 213.67496 -356.725474)
						(mid 209.63636 -360.764074)
						(end 213.67496 -364.802674)
					)
				)
			)
		)
		(zone
			(layer "B.Cu")
			(hatch none 0.5)
			(connect_pads
				(clearance 0)
			)
			(min_thickness 0.25)
			(keepout
				(tracks not_allowed)
				(vias allowed)
				(pads allowed)
				(copperpour not_allowed)
				(footprints allowed)
			)
			(placement
				(enabled no)
				(sheetname "")
			)
			(fill
				(thermal_gap 0.5)
				(thermal_bridge_width 0.5)
				(island_removal_mode 0)
			)
			(polygon
				(pts
					(arc
						(start 213.67496 -365.285274)
						(mid 218.19616 -360.764074)
						(end 213.67496 -356.242874)
					)
					(arc
						(start 213.67496 -356.725474)
						(mid 217.71356 -360.764074)
						(end 213.67496 -364.802674)
					)
				)
			)
		)
	)
	(footprint ""
		(layer "F.Cu")
		(at 278.254206 -431.191416 -90)
		(property "Reference" "C69"
			(at 0 0 270)
			(layer "F.SilkS")
			(hide yes)
			(effects
				(font
					(size 1.27 1.27)
				)
			)
		)
		(property "Value" ""
			(at 0 0 270)
			(layer "F.Fab")
			(effects
				(font
					(size 1.27 1.27)
				)
			)
		)
		(duplicate_pad_numbers_are_jumpers no)
		(fp_line
			(start -0.7874 0.4064)
			(end -0.7874 -0.4064)
			(stroke
				(width 0.1524)
				(type default)
			)
			(layer "F.SilkS")
		)
		(fp_line
			(start 0.7874 0.4064)
			(end -0.7874 0.4064)
			(stroke
				(width 0.1524)
				(type default)
			)
			(layer "F.SilkS")
		)
		(fp_line
			(start -0.7874 -0.4064)
			(end 0.7874 -0.4064)
			(stroke
				(width 0.1524)
				(type default)
			)
			(layer "F.SilkS")
		)
		(fp_line
			(start 0.7874 -0.4064)
			(end 0.7874 0.4064)
			(stroke
				(width 0.1524)
				(type default)
			)
			(layer "F.SilkS")
		)
		(fp_line
			(start -0.67945 0.3048)
			(end -0.67945 -0.305054)
			(stroke
				(width 0.1)
				(type default)
			)
			(layer "F.Fab")
		)
		(fp_line
			(start -0.12065 0.3048)
			(end -0.67945 0.3048)
			(stroke
				(width 0.1)
				(type default)
			)
			(layer "F.Fab")
		)
		(fp_line
			(start 0.120396 0.3048)
			(end 0.120396 0.2794)
			(stroke
				(width 0.1)
				(type default)
			)
			(layer "F.Fab")
		)
		(fp_line
			(start 0.67945 0.3048)
			(end 0.120396 0.3048)
			(stroke
				(width 0.1)
				(type default)
			)
			(layer "F.Fab")
		)
		(fp_line
			(start -0.12065 0.2794)
			(end -0.12065 0.3048)
			(stroke
				(width 0.1)
				(type default)
			)
			(layer "F.Fab")
		)
		(fp_line
			(start 0.120396 0.2794)
			(end -0.12065 0.2794)
			(stroke
				(width 0.1)
				(type default)
			)
			(layer "F.Fab")
		)
		(fp_line
			(start -0.12065 -0.2794)
			(end 0.12065 -0.2794)
			(stroke
				(width 0.1)
				(type default)
			)
			(layer "F.Fab")
		)
		(fp_line
			(start 0.12065 -0.2794)
			(end 0.12065 -0.3048)
			(stroke
				(width 0.1)
				(type default)
			)
			(layer "F.Fab")
		)
		(fp_line
			(start 0.12065 -0.3048)
			(end 0.67945 -0.3048)
			(stroke
				(width 0.1)
				(type default)
			)
			(layer "F.Fab")
		)
		(fp_line
			(start 0.67945 -0.3048)
			(end 0.67945 0.3048)
			(stroke
				(width 0.1)
				(type default)
			)
			(layer "F.Fab")
		)
		(fp_line
			(start -0.67945 -0.305054)
			(end -0.12065 -0.305054)
			(stroke
				(width 0.1)
				(type default)
			)
			(layer "F.Fab")
		)
		(fp_line
			(start -0.12065 -0.305054)
			(end -0.12065 -0.2794)
			(stroke
				(width 0.1)
				(type default)
			)
			(layer "F.Fab")
		)
		(pad "1" smd circle
			(at -0.40005 0 270)
			(size 0 0)
			(layers "F.Cu" "F.Mask" "F.Paste")
			(net "P3V3_AUX")
		)
		(pad "2" smd circle
			(at 0.40005 0 270)
			(size 0 0)
			(layers "F.Cu" "F.Mask" "F.Paste")
			(net "GND")
		)
	)
)
